# SCM (Grand Teton) — schematic netlist excerpt (pin names and nets, part order shuffled) for the footprints in the layout excerpt that follows; sources: Cadence DE-HDL packaged netlist, KiCad conversion of 12092022_DA0F0TMDCD0_F0T_Management_Board_D_brd_V3_OCP.brd

R783  Q_RES  0 5% CHIP  pkg 0402LF  page 17 : A = P1V8_AUX ; B = ADCVREFEXT0
C1  Q_CAP  4.7UF 25V 10% X6S  pkg C0603  page 20 : A = P1V2_AUX ; B = GND

(kicad_pcb
	(version 20260206)
	(generator "pcbnew")
	(generator_version "10.0")
	(general
		(thickness 1.6)
		(legacy_teardrops no)
	)
	(paper "A4")
	(title_block
		(title "12092022_DA0F0TMDCD0_F0T_Management_Board_D_brd_V3_OCP.brd")
		(comment 1 "Grand Teton / footprints 984-985 of 1440")
	)
	(layers
		(0 "F.Cu" signal "TOP")
		(4 "In1.Cu" signal "GND")
		(6 "In2.Cu" signal "IN1")
		(8 "In3.Cu" signal "GND1")
		(10 "In4.Cu" signal "IN2")
		(12 "In5.Cu" signal "VCC")
		(14 "In6.Cu" signal "VCC1")
		(16 "In7.Cu" signal "IN3")
		(18 "In8.Cu" signal "GND2")
		(20 "In9.Cu" signal "IN4")
		(22 "In10.Cu" signal "GND3")
		(2 "B.Cu" signal "BOTTOM")
		(9 "F.Adhes" user "F.Adhesive")
		(11 "B.Adhes" user "B.Adhesive")
		(13 "F.Paste" user "Package Geometry/Pastemask Top")
		(15 "B.Paste" user "Package Geometry/Pastemask Bottom")
		(5 "F.SilkS" user "Ref Des/Silkscreen Top")
		(7 "B.SilkS" user "Ref Des/Silkscreen Bottom")
		(1 "F.Mask" user "Board Geometry/Soldermask Top")
		(3 "B.Mask" user "Board Geometry/Soldermask Bottom")
		(17 "Dwgs.User" user "User.Drawings")
		(19 "Cmts.User" user "User.Comments")
		(21 "Eco1.User" user "User.Eco1")
		(23 "Eco2.User" user "User.Eco2")
		(25 "Edge.Cuts" user "Board Geometry/Outline")
		(27 "Margin" user)
		(31 "F.CrtYd" user "Package Geometry/Place Bound Top")
		(29 "B.CrtYd" user "Package Geometry/Place Bound Bottom")
		(35 "F.Fab" user "Ref Des/Assembly Top")
		(33 "B.Fab" user "Ref Des/Assembly Bottom")
	)
	(footprint ""
		(layer "B.Cu")
		(at 56.861964 -70.046342)
		(property "Reference" "R783"
			(at 0 0 0)
			(layer "B.SilkS")
			(hide yes)
			(effects
				(font
					(size 1.27 1.27)
				)
				(justify mirror)
			)
		)
		(property "Value" ""
			(at 0 0 0)
			(layer "B.Fab")
			(effects
				(font
					(size 1.27 1.27)
				)
				(justify mirror)
			)
		)
		(duplicate_pad_numbers_are_jumpers no)
		(fp_line
			(start -0.7874 -0.4064)
			(end -0.7874 0.4064)
			(stroke
				(width 0.1524)
				(type default)
			)
			(layer "B.SilkS")
		)
		(fp_line
			(start -0.7874 0.4064)
			(end 0.7874 0.4064)
			(stroke
				(width 0.1524)
				(type default)
			)
			(layer "B.SilkS")
		)
		(fp_line
			(start 0.7874 -0.4064)
			(end -0.7874 -0.4064)
			(stroke
				(width 0.1524)
				(type default)
			)
			(layer "B.SilkS")
		)
		(fp_line
			(start 0.7874 0.4064)
			(end 0.7874 -0.4064)
			(stroke
				(width 0.1524)
				(type default)
			)
			(layer "B.SilkS")
		)
		(fp_line
			(start -0.67945 -0.3048)
			(end -0.67945 0.3048)
			(stroke
				(width 0.1)
				(type default)
			)
			(layer "B.Fab")
		)
		(fp_line
			(start -0.67945 0.3048)
			(end -0.120396 0.3048)
			(stroke
				(width 0.1)
				(type default)
			)
			(layer "B.Fab")
		)
		(fp_line
			(start -0.12065 -0.3048)
			(end -0.67945 -0.3048)
			(stroke
				(width 0.1)
				(type default)
			)
			(layer "B.Fab")
		)
		(fp_line
			(start -0.12065 -0.2794)
			(end -0.12065 -0.3048)
			(stroke
				(width 0.1)
				(type default)
			)
			(layer "B.Fab")
		)
		(fp_line
			(start -0.120396 0.2794)
			(end 0.12065 0.2794)
			(stroke
				(width 0.1)
				(type default)
			)
			(layer "B.Fab")
		)
		(fp_line
			(start -0.120396 0.3048)
			(end -0.120396 0.2794)
			(stroke
				(width 0.1)
				(type default)
			)
			(layer "B.Fab")
		)
		(fp_line
			(start 0.12065 -0.305054)
			(end 0.12065 -0.2794)
			(stroke
				(width 0.1)
				(type default)
			)
			(layer "B.Fab")
		)
		(fp_line
			(start 0.12065 -0.2794)
			(end -0.12065 -0.2794)
			(stroke
				(width 0.1)
				(type default)
			)
			(layer "B.Fab")
		)
		(fp_line
			(start 0.12065 0.2794)
			(end 0.12065 0.3048)
			(stroke
				(width 0.1)
				(type default)
			)
			(layer "B.Fab")
		)
		(fp_line
			(start 0.12065 0.3048)
			(end 0.67945 0.3048)
			(stroke
				(width 0.1)
				(type default)
			)
			(layer "B.Fab")
		)
		(fp_line
			(start 0.67945 -0.305054)
			(end 0.12065 -0.305054)
			(stroke
				(width 0.1)
				(type default)
			)
			(layer "B.Fab")
		)
		(fp_line
			(start 0.67945 0.3048)
			(end 0.67945 -0.305054)
			(stroke
				(width 0.1)
				(type default)
			)
			(layer "B.Fab")
		)
		(pad "1" smd circle
			(at 0.40005 0 180)
			(size 0 0)
			(layers "B.Cu" "B.Mask" "B.Paste")
			(net "P1V8_AUX")
		)
		(pad "2" smd circle
			(at -0.40005 0 180)
			(size 0 0)
			(layers "B.Cu" "B.Mask" "B.Paste")
			(net "ADCVREFEXT0")
		)
	)
	(footprint ""
		(layer "B.Cu")
		(at 82.933794 -49.907444 180)
		(property "Reference" "C1"
			(at 0 0 0)
			(layer "B.SilkS")
			(hide yes)
			(effects
				(font
					(size 1.27 1.27)
				)
				(justify mirror)
			)
		)
		(property "Value" ""
			(at 0 0 0)
			(layer "B.Fab")
			(effects
				(font
					(size 1.27 1.27)
				)
				(justify mirror)
			)
		)
		(duplicate_pad_numbers_are_jumpers no)
		(fp_line
			(start 1.2954 0.5842)
			(end 1.2954 -0.5842)
			(stroke
				(width 0.1524)
				(type default)
			)
			(layer "B.SilkS")
		)
		(fp_line
			(start 1.2954 -0.5842)
			(end -1.2954 -0.5842)
			(stroke
				(width 0.1524)
				(type default)
			)
			(layer "B.SilkS")
		)
		(fp_line
			(start 0 -0.5842)
			(end 0 0.5842)
			(stroke
				(width 0.1524)
				(type default)
			)
			(layer "B.SilkS")
		)
		(fp_line
			(start -1.2954 0.5842)
			(end 1.2954 0.5842)
			(stroke
				(width 0.1524)
				(type default)
			)
			(layer "B.SilkS")
		)
		(fp_line
			(start -1.2954 -0.5842)
			(end -1.2954 0.5842)
			(stroke
				(width 0.1524)
				(type default)
			)
			(layer "B.SilkS")
		)
		(fp_line
			(start 1.1938 0.4064)
			(end 1.1938 -0.4064)
			(stroke
				(width 0.1)
				(type default)
			)
			(layer "B.Fab")
		)
		(fp_line
			(start 1.1938 -0.4064)
			(end 0.8636 -0.4064)
			(stroke
				(width 0.1)
				(type default)
			)
			(layer "B.Fab")
		)
		(fp_line
			(start 0.8636 0.4572)
			(end 0.8636 0.4064)
			(stroke
				(width 0.1)
				(type default)
			)
			(layer "B.Fab")
		)
		(fp_line
			(start 0.8636 0.4064)
			(end 1.1938 0.4064)
			(stroke
				(width 0.1)
				(type default)
			)
			(layer "B.Fab")
		)
		(fp_line
			(start 0.8636 -0.4064)
			(end 0.8636 -0.4572)
			(stroke
				(width 0.1)
				(type default)
			)
			(layer "B.Fab")
		)
		(fp_line
			(start 0.8636 -0.4572)
			(end -0.8636 -0.4572)
			(stroke
				(width 0.1)
				(type default)
			)
			(layer "B.Fab")
		)
		(fp_line
			(start -0.8636 0.4572)
			(end 0.8636 0.4572)
			(stroke
				(width 0.1)
				(type default)
			)
			(layer "B.Fab")
		)
		(fp_line
			(start -0.8636 0.4064)
			(end -0.8636 0.4572)
			(stroke
				(width 0.1)
				(type default)
			)
			(layer "B.Fab")
		)
		(fp_line
			(start -0.8636 -0.4064)
			(end -1.1938 -0.4064)
			(stroke
				(width 0.1)
				(type default)
			)
			(layer "B.Fab")
		)
		(fp_line
			(start -0.8636 -0.4572)
			(end -0.8636 -0.4064)
			(stroke
				(width 0.1)
				(type default)
			)
			(layer "B.Fab")
		)
		(fp_line
			(start -1.1938 0.4064)
			(end -0.8636 0.4064)
			(stroke
				(width 0.1)
				(type default)
			)
			(layer "B.Fab")
		)
		(fp_line
			(start -1.1938 -0.4064)
			(end -1.1938 0.4064)
			(stroke
				(width 0.1)
				(type default)
			)
			(layer "B.Fab")
		)
		(pad "1" smd rect
			(at 0.7366 0 90)
			(size 0.7112 0.8128)
			(layers "B.Cu" "B.Mask" "B.Paste")
			(net "P1V2_AUX")
		)
		(pad "2" smd rect
			(at -0.7366 0 90)
			(size 0.7112 0.8128)
			(layers "B.Cu" "B.Mask" "B.Paste")
			(net "GND")
		)
	)
)
